(kicad_pcb
	(version 20241229)
	(generator "pcbnew")
	(generator_version "9.0")
	(general
		(thickness 1.711)
		(legacy_teardrops no)
	)
	(paper "A4")
	(title_block
		(title "Antmicro Baseboard for Jetson AGX Thor")
		(date "2026-02-18")
		(rev "1.1.0")
		(company "Antmicro Ltd")
		(comment 1 "www.antmicro.com")
		(comment 9 "footprints 519-523 of 1170")
	)
	(layers
		(0 "F.Cu" signal)
		(4 "In1.Cu" signal)
		(6 "In2.Cu" signal)
		(8 "In3.Cu" signal)
		(10 "In4.Cu" jumper)
		(12 "In5.Cu" signal)
		(14 "In6.Cu" signal)
		(16 "In7.Cu" signal)
		(18 "In8.Cu" signal)
		(2 "B.Cu" signal)
		(9 "F.Adhes" user "F.Adhesive")
		(11 "B.Adhes" user "B.Adhesive")
		(13 "F.Paste" user)
		(15 "B.Paste" user)
		(5 "F.SilkS" user "F.Silkscreen")
		(7 "B.SilkS" user "B.Silkscreen")
		(1 "F.Mask" user)
		(3 "B.Mask" user)
		(17 "Dwgs.User" user "User.Drawings")
		(19 "Cmts.User" user "User.Comments")
		(21 "Eco1.User" user "User.Eco1")
		(23 "Eco2.User" user "User.Eco2")
		(25 "Edge.Cuts" user)
		(27 "Margin" user)
		(31 "F.CrtYd" user "F.Courtyard")
		(29 "B.CrtYd" user "B.Courtyard")
		(35 "F.Fab" user)
		(33 "B.Fab" user)
	)
	(footprint "antmicro-footprints:R_0402_1005Metric"
		(layer "F.Cu")
		(at 100.12 123.1 180)
		(descr "Resistor SMD 0402")
		(tags "resistor SMD 0402")
		(property "Reference" "R320"
			(at -1.8 -0.6 0)
			(layer "F.SilkS")
			(effects
				(font
					(size 0.7 0.7)
					(thickness 0.15)
				)
				(justify right top)
			)
		)
		(property "Value" "R_0R_0402"
			(at -1.011843 1.772046 0)
			(layer "F.Fab")
			(effects
				(font
					(size 0.7 0.7)
					(thickness 0.15)
				)
				(justify right top)
			)
		)
		(property "Datasheet" "https://industrial.panasonic.com/cdbs/www-data/pdf/RDA0000/AOA0000C301.pdf"
			(at 0 0 0)
			(layer "F.Fab")
			(hide yes)
			(effects
				(font
					(size 1.27 1.27)
					(thickness 0.15)
				)
			)
		)
		(property "Description" "SMD Chip Resistor, Jumper, 0 ohm, 100 mW, 0402 [1005 Metric], Thick Film, General Purpose"
			(at 0 0 0)
			(layer "F.Fab")
			(hide yes)
			(effects
				(font
					(size 1.27 1.27)
					(thickness 0.15)
				)
			)
		)
		(property "MPN" "ERJ2GE0R00X"
			(at 0 0 180)
			(unlocked yes)
			(layer "F.Fab")
			(hide yes)
			(effects
				(font
					(size 1 1)
					(thickness 0.15)
				)
			)
		)
		(property "Manufacturer" "Panasonic"
			(at 0 0 180)
			(unlocked yes)
			(layer "F.Fab")
			(hide yes)
			(effects
				(font
					(size 1 1)
					(thickness 0.15)
				)
			)
		)
		(property "License" "Apache-2.0"
			(at 0 0 180)
			(unlocked yes)
			(layer "F.Fab")
			(hide yes)
			(effects
				(font
					(size 1 1)
					(thickness 0.15)
				)
			)
		)
		(property "Author" "Antmicro"
			(at 0 0 180)
			(unlocked yes)
			(layer "F.Fab")
			(hide yes)
			(effects
				(font
					(size 1 1)
					(thickness 0.15)
				)
			)
		)
		(property "Val" "0R"
			(at 0 0 180)
			(unlocked yes)
			(layer "F.Fab")
			(hide yes)
			(effects
				(font
					(size 1 1)
					(thickness 0.15)
				)
			)
		)
		(property "Tolerance" "~"
			(at 0 0 180)
			(unlocked yes)
			(layer "F.Fab")
			(hide yes)
			(effects
				(font
					(size 1 1)
					(thickness 0.15)
				)
			)
		)
		(property "Current" "1A"
			(at 0 0 180)
			(unlocked yes)
			(layer "F.Fab")
			(hide yes)
			(effects
				(font
					(size 1 1)
					(thickness 0.15)
				)
			)
		)
		(sheetname "/Expansion connector/")
		(sheetfile "expansion_connector.kicad_sch")
		(attr smd exclude_from_pos_files exclude_from_bom dnp)
		(fp_poly
			(pts
				(xy -0.925 -0.47) (xy 0.925 -0.47) (xy 0.925 0.47) (xy -0.925 0.47)
			)
			(stroke
				(width 0.05)
				(type default)
			)
			(fill no)
			(layer "F.CrtYd")
		)
		(fp_poly
			(pts
				(xy -0.5 -0.25) (xy 0.5 -0.25) (xy 0.5 0.25) (xy -0.5 0.25)
			)
			(stroke
				(width 0.15)
				(type solid)
			)
			(fill no)
			(layer "F.Fab")
		)
		(fp_text user "License: Apache-2.0"
			(at -0.949999 5.169 0)
			(layer "F.Fab")
			(effects
				(font
					(size 0.7 0.7)
					(thickness 0.15)
				)
				(justify right top)
			)
		)
		(fp_text user "${REFERENCE}"
			(at -0.95 3.168 0)
			(layer "F.Fab")
			(effects
				(font
					(size 0.7 0.7)
					(thickness 0.15)
				)
				(justify right top)
			)
		)
		(fp_text user "Author: Antmicro"
			(at -0.95 4.169 0)
			(layer "F.Fab")
			(effects
				(font
					(size 0.7 0.7)
					(thickness 0.15)
				)
				(justify right top)
			)
		)
		(pad "1" smd roundrect
			(at -0.48 0 180)
			(size 0.59 0.64)
			(layers "F.Cu" "F.Mask" "F.Paste")
			(roundrect_rratio 0.25)
			(net 2 "+3V3")
			(pintype "passive")
		)
		(pad "2" smd roundrect
			(at 0.48 0 180)
			(size 0.59 0.64)
			(layers "F.Cu" "F.Mask" "F.Paste")
			(roundrect_rratio 0.25)
			(net 148 "/Expansion connector/+3V3_AUX")
			(pintype "passive")
		)
	)
	(footprint "antmicro-footprints:R_0402_1005Metric"
		(layer "F.Cu")
		(at 97.1 61.9 180)
		(descr "Resistor SMD 0402")
		(tags "resistor SMD 0402")
		(property "Reference" "R44"
			(at -3 0.4 0)
			(layer "F.SilkS")
			(effects
				(font
					(size 0.7 0.7)
					(thickness 0.15)
				)
				(justify right top)
			)
		)
		(property "Value" "R_0R_0402"
			(at -1.011843 1.772047 0)
			(layer "F.Fab")
			(effects
				(font
					(size 0.7 0.7)
					(thickness 0.15)
				)
				(justify right top)
			)
		)
		(property "Datasheet" "https://industrial.panasonic.com/cdbs/www-data/pdf/RDA0000/AOA0000C301.pdf"
			(at 0 0 0)
			(layer "F.Fab")
			(hide yes)
			(effects
				(font
					(size 1.27 1.27)
					(thickness 0.15)
				)
			)
		)
		(property "Description" "SMD Chip Resistor, Jumper, 0 ohm, 100 mW, 0402 [1005 Metric], Thick Film, General Purpose"
			(at 0 0 0)
			(layer "F.Fab")
			(hide yes)
			(effects
				(font
					(size 1.27 1.27)
					(thickness 0.15)
				)
			)
		)
		(property "MPN" "ERJ2GE0R00X"
			(at 0 0 180)
			(unlocked yes)
			(layer "F.Fab")
			(hide yes)
			(effects
				(font
					(size 1 1)
					(thickness 0.15)
				)
			)
		)
		(property "Manufacturer" "Panasonic"
			(at 0 0 180)
			(unlocked yes)
			(layer "F.Fab")
			(hide yes)
			(effects
				(font
					(size 1 1)
					(thickness 0.15)
				)
			)
		)
		(property "License" "Apache-2.0"
			(at 0 0 180)
			(unlocked yes)
			(layer "F.Fab")
			(hide yes)
			(effects
				(font
					(size 1 1)
					(thickness 0.15)
				)
			)
		)
		(property "Author" "Antmicro"
			(at 0 0 180)
			(unlocked yes)
			(layer "F.Fab")
			(hide yes)
			(effects
				(font
					(size 1 1)
					(thickness 0.15)
				)
			)
		)
		(property "Val" "0R"
			(at 0 0 180)
			(unlocked yes)
			(layer "F.Fab")
			(hide yes)
			(effects
				(font
					(size 1 1)
					(thickness 0.15)
				)
			)
		)
		(property "Tolerance" "~"
			(at 0 0 180)
			(unlocked yes)
			(layer "F.Fab")
			(hide yes)
			(effects
				(font
					(size 1 1)
					(thickness 0.15)
				)
			)
		)
		(property "Current" "1A"
			(at 0 0 180)
			(unlocked yes)
			(layer "F.Fab")
			(hide yes)
			(effects
				(font
					(size 1 1)
					(thickness 0.15)
				)
			)
		)
		(sheetname "/SoM_Power/")
		(sheetfile "som_power.kicad_sch")
		(attr smd)
		(fp_rect
			(start -0.925 -0.47)
			(end 0.925 0.47)
			(stroke
				(width 0.05)
				(type default)
			)
			(fill no)
			(layer "F.CrtYd")
		)
		(fp_rect
			(start -0.5 -0.25)
			(end 0.5 0.25)
			(stroke
				(width 0.15)
				(type solid)
			)
			(fill no)
			(layer "F.Fab")
		)
		(fp_text user "${REFERENCE}"
			(at -0.95 3.168 0)
			(layer "F.Fab")
			(effects
				(font
					(size 0.7 0.7)
					(thickness 0.15)
				)
				(justify right top)
			)
		)
		(fp_text user "Author: Antmicro"
			(at -0.95 4.169 0)
			(layer "F.Fab")
			(effects
				(font
					(size 0.7 0.7)
					(thickness 0.15)
				)
				(justify right top)
			)
		)
		(fp_text user "License: Apache-2.0"
			(at -0.95 5.169 0)
			(layer "F.Fab")
			(effects
				(font
					(size 0.7 0.7)
					(thickness 0.15)
				)
				(justify right top)
			)
		)
		(pad "1" smd roundrect
			(at -0.48 0 180)
			(size 0.59 0.64)
			(layers "F.Cu" "F.Mask" "F.Paste")
			(roundrect_rratio 0.25)
			(net 1379 "Net-(Q30-D)")
			(pintype "passive")
		)
		(pad "2" smd roundrect
			(at 0.48 0 180)
			(size 0.59 0.64)
			(layers "F.Cu" "F.Mask" "F.Paste")
			(roundrect_rratio 0.25)
			(net 1032 "/SoM_Power/~{FORCE_SHDN}")
			(pintype "passive")
		)
	)
	(footprint "antmicro-footprints:C_0402_1005Metric"
		(layer "F.Cu")
		(at 210.25 133.1 180)
		(descr "Capacitor SMD 0402")
		(tags "capacitor SMD 0402")
		(property "Reference" "C87"
			(at 3.05 0.4 0)
			(layer "F.SilkS")
			(effects
				(font
					(size 0.7 0.7)
					(thickness 0.15)
				)
				(justify right top)
			)
		)
		(property "Value" "C_100n_0402"
			(at -1.022927 2.155213 0)
			(layer "F.Fab")
			(effects
				(font
					(size 0.7 0.7)
					(thickness 0.15)
				)
				(justify right top)
			)
		)
		(property "Datasheet" "https://www.murata.com/products/productdetail?partno=GRM155R61H104KE14%23"
			(at 0 0 0)
			(layer "F.Fab")
			(hide yes)
			(effects
				(font
					(size 1.27 1.27)
					(thickness 0.15)
				)
			)
		)
		(property "Description" "SMD Multilayer Ceramic Capacitor, 0.1 µF, 50 V, 0402 [1005 Metric], ± 10%, X5R, GRM Series"
			(at 0 0 0)
			(layer "F.Fab")
			(hide yes)
			(effects
				(font
					(size 1.27 1.27)
					(thickness 0.15)
				)
			)
		)
		(property "MPN" "GRM155R61H104KE14D"
			(at 0 0 180)
			(unlocked yes)
			(layer "F.Fab")
			(hide yes)
			(effects
				(font
					(size 1 1)
					(thickness 0.15)
				)
			)
		)
		(property "Val" "100n"
			(at 0 0 180)
			(unlocked yes)
			(layer "F.Fab")
			(hide yes)
			(effects
				(font
					(size 1 1)
					(thickness 0.15)
				)
			)
		)
		(property "Voltage" "50V"
			(at 0 0 180)
			(unlocked yes)
			(layer "F.Fab")
			(hide yes)
			(effects
				(font
					(size 1 1)
					(thickness 0.15)
				)
			)
		)
		(property "Dielectric" "X5R"
			(at 0 0 180)
			(unlocked yes)
			(layer "F.Fab")
			(hide yes)
			(effects
				(font
					(size 1 1)
					(thickness 0.15)
				)
			)
		)
		(property "Manufacturer" "Murata"
			(at 0 0 180)
			(unlocked yes)
			(layer "F.Fab")
			(hide yes)
			(effects
				(font
					(size 1 1)
					(thickness 0.15)
				)
			)
		)
		(property "License" "Apache-2.0"
			(at 0 0 180)
			(unlocked yes)
			(layer "F.Fab")
			(hide yes)
			(effects
				(font
					(size 1 1)
					(thickness 0.15)
				)
			)
		)
		(property "Author" "Antmicro"
			(at 0 0 180)
			(unlocked yes)
			(layer "F.Fab")
			(hide yes)
			(effects
				(font
					(size 1 1)
					(thickness 0.15)
				)
			)
		)
		(sheetname "/USB Hub/")
		(sheetfile "usb_hub.kicad_sch")
		(attr smd)
		(fp_poly
			(pts
				(xy -0.925 -0.47) (xy 0.925 -0.47) (xy 0.925 0.47) (xy -0.925 0.47)
			)
			(stroke
				(width 0.05)
				(type default)
			)
			(fill no)
			(layer "F.CrtYd")
		)
		(fp_line
			(start 0.504 0.248)
			(end -0.494 0.248)
			(stroke
				(width 0.15)
				(type solid)
			)
			(layer "F.Fab")
		)
		(fp_line
			(start 0.504 -0.25)
			(end 0.504 0.248)
			(stroke
				(width 0.15)
				(type solid)
			)
			(layer "F.Fab")
		)
		(fp_line
			(start -0.494 0.248)
			(end -0.494 -0.25)
			(stroke
				(width 0.15)
				(type solid)
			)
			(layer "F.Fab")
		)
		(fp_line
			(start -0.494 -0.25)
			(end 0.504 -0.25)
			(stroke
				(width 0.15)
				(type solid)
			)
			(layer "F.Fab")
		)
		(fp_text user "${REFERENCE}"
			(at -0.939 4.599 0)
			(layer "F.Fab")
			(effects
				(font
					(size 0.7 0.7)
					(thickness 0.15)
				)
				(justify right top)
			)
		)
		(fp_text user "Author: Antmicro"
			(at -0.939 3.399 0)
			(layer "F.Fab")
			(effects
				(font
					(size 0.7 0.7)
					(thickness 0.15)
				)
				(justify right top)
			)
		)
		(fp_text user "License: Apache-2.0"
			(at -0.939 5.799 0)
			(layer "F.Fab")
			(effects
				(font
					(size 0.7 0.7)
					(thickness 0.15)
				)
				(justify right top)
			)
		)
		(pad "1" smd roundrect
			(at -0.48 0 180)
			(size 0.59 0.64)
			(layers "F.Cu" "F.Mask" "F.Paste")
			(roundrect_rratio 0.25)
			(net 1 "GND")
			(pintype "passive")
		)
		(pad "2" smd roundrect
			(at 0.48 0 180)
			(size 0.59 0.64)
			(layers "F.Cu" "F.Mask" "F.Paste")
			(roundrect_rratio 0.25)
			(net 2 "+3V3")
			(pintype "passive")
		)
	)
	(footprint "antmicro-footprints:R_0402_1005Metric"
		(layer "F.Cu")
		(at 195.1 130.3)
		(descr "Resistor SMD 0402")
		(tags "resistor SMD 0402")
		(property "Reference" "R40"
			(at -1.050001 5.3 0)
			(layer "F.SilkS")
			(effects
				(font
					(size 0.7 0.7)
					(thickness 0.15)
				)
				(justify left bottom)
			)
		)
		(property "Value" "R_0R_0402"
			(at -1.011843 1.772046 0)
			(layer "F.Fab")
			(effects
				(font
					(size 0.7 0.7)
					(thickness 0.15)
				)
				(justify left bottom)
			)
		)
		(property "Datasheet" "https://industrial.panasonic.com/cdbs/www-data/pdf/RDA0000/AOA0000C301.pdf"
			(at 0 0 0)
			(layer "F.Fab")
			(hide yes)
			(effects
				(font
					(size 1.27 1.27)
					(thickness 0.15)
				)
			)
		)
		(property "Description" "SMD Chip Resistor, Jumper, 0 ohm, 100 mW, 0402 [1005 Metric], Thick Film, General Purpose"
			(at 0 0 0)
			(layer "F.Fab")
			(hide yes)
			(effects
				(font
					(size 1.27 1.27)
					(thickness 0.15)
				)
			)
		)
		(property "Manufacturer" "Panasonic"
			(at 0 0 0)
			(unlocked yes)
			(layer "F.Fab")
			(hide yes)
			(effects
				(font
					(size 1 1)
					(thickness 0.15)
				)
			)
		)
		(property "MPN" "ERJ2GE0R00X"
			(at 0 0 0)
			(unlocked yes)
			(layer "F.Fab")
			(hide yes)
			(effects
				(font
					(size 1 1)
					(thickness 0.15)
				)
			)
		)
		(property "Val" "0R"
			(at 0 0 0)
			(unlocked yes)
			(layer "F.Fab")
			(hide yes)
			(effects
				(font
					(size 1 1)
					(thickness 0.15)
				)
			)
		)
		(property "License" "Apache-2.0"
			(at 0 0 0)
			(unlocked yes)
			(layer "F.Fab")
			(hide yes)
			(effects
				(font
					(size 1 1)
					(thickness 0.15)
				)
			)
		)
		(property "Author" "Antmicro"
			(at 0 0 0)
			(unlocked yes)
			(layer "F.Fab")
			(hide yes)
			(effects
				(font
					(size 1 1)
					(thickness 0.15)
				)
			)
		)
		(property "Tolerance" "~"
			(at 0 0 0)
			(unlocked yes)
			(layer "F.Fab")
			(hide yes)
			(effects
				(font
					(size 1 1)
					(thickness 0.15)
				)
			)
		)
		(property "Current" "1A"
			(at 0 0 0)
			(unlocked yes)
			(layer "F.Fab")
			(hide yes)
			(effects
				(font
					(size 1 1)
					(thickness 0.15)
				)
			)
		)
		(sheetname "/USB Hub/")
		(sheetfile "usb_hub.kicad_sch")
		(attr smd exclude_from_pos_files exclude_from_bom dnp)
		(fp_poly
			(pts
				(xy -0.925 -0.47) (xy -0.925 0.47) (xy 0.925 0.47) (xy 0.925 -0.47)
			)
			(stroke
				(width 0.05)
				(type default)
			)
			(fill no)
			(layer "F.CrtYd")
		)
		(fp_poly
			(pts
				(xy -0.5 -0.25) (xy -0.5 0.25) (xy 0.5 0.25) (xy 0.5 -0.25)
			)
			(stroke
				(width 0.15)
				(type solid)
			)
			(fill no)
			(layer "F.Fab")
		)
		(fp_text user "Author: Antmicro"
			(at -0.95 4.169 0)
			(layer "F.Fab")
			(effects
				(font
					(size 0.7 0.7)
					(thickness 0.15)
				)
				(justify left bottom)
			)
		)
		(fp_text user "License: Apache-2.0"
			(at -0.949999 5.169 0)
			(layer "F.Fab")
			(effects
				(font
					(size 0.7 0.7)
					(thickness 0.15)
				)
				(justify left bottom)
			)
		)
		(fp_text user "${REFERENCE}"
			(at -0.95 3.168 0)
			(layer "F.Fab")
			(effects
				(font
					(size 0.7 0.7)
					(thickness 0.15)
				)
				(justify left bottom)
			)
		)
		(pad "1" smd roundrect
			(at -0.48 0)
			(size 0.59 0.64)
			(layers "F.Cu" "F.Mask" "F.Paste")
			(roundrect_rratio 0.25)
			(net 850 "/I2C_{SYS}.SDA")
			(pintype "passive")
		)
		(pad "2" smd roundrect
			(at 0.48 0)
			(size 0.59 0.64)
			(layers "F.Cu" "F.Mask" "F.Paste")
			(roundrect_rratio 0.25)
			(net 1233 "Net-(U21-PF19)")
			(pintype "passive")
		)
	)
	(footprint "antmicro-footprints:C_0805_2012Metric"
		(layer "F.Cu")
		(at 111.380001 56.74 -90)
		(descr "Capacitor SMD 0805")
		(tags "capacitor SMD 0805")
		(property "Reference" "C380"
			(at -1.87 1.910001 180)
			(layer "F.SilkS")
			(effects
				(font
					(size 0.7 0.7)
					(thickness 0.15)
				)
				(justify left bottom)
			)
		)
		(property "Value" "C_22u_25V_0805"
			(at -2.055717 1.963153 90)
			(layer "F.Fab")
			(effects
				(font
					(size 0.7 0.7)
					(thickness 0.15)
				)
				(justify right top)
			)
		)
		(property "Datasheet" "https://product.samsungsem.com/mlcc/CL21A226MAYNNN.do"
			(at 0 0 90)
			(layer "F.Fab")
			(hide yes)
			(effects
				(font
					(size 1.27 1.27)
					(thickness 0.15)
				)
			)
		)
		(property "Description" "SMT Multilayer Ceramic Capacitor, 22uF, +/-20%, 25V, X5R, 0805 [2012 Metric]"
			(at 0 0 90)
			(layer "F.Fab")
			(hide yes)
			(effects
				(font
					(size 1.27 1.27)
					(thickness 0.15)
				)
			)
		)
		(property "MPN" "CL21A226MAYNNNE"
			(at 0 0 270)
			(unlocked yes)
			(layer "F.Fab")
			(hide yes)
			(effects
				(font
					(size 1 1)
					(thickness 0.15)
				)
			)
		)
		(property "Manufacturer" "Samsung Electro-Mechanics"
			(at 0 0 270)
			(unlocked yes)
			(layer "F.Fab")
			(hide yes)
			(effects
				(font
					(size 1 1)
					(thickness 0.15)
				)
			)
		)
		(property "License" "Apache-2.0"
			(at 0 0 270)
			(unlocked yes)
			(layer "F.Fab")
			(hide yes)
			(effects
				(font
					(size 1 1)
					(thickness 0.15)
				)
			)
		)
		(property "Author" "Antmicro"
			(at 0 0 270)
			(unlocked yes)
			(layer "F.Fab")
			(hide yes)
			(effects
				(font
					(size 1 1)
					(thickness 0.15)
				)
			)
		)
		(property "Val" "22u"
			(at 0 0 270)
			(unlocked yes)
			(layer "F.Fab")
			(hide yes)
			(effects
				(font
					(size 1 1)
					(thickness 0.15)
				)
			)
		)
		(property "Voltage" "25V"
			(at 0 0 270)
			(unlocked yes)
			(layer "F.Fab")
			(hide yes)
			(effects
				(font
					(size 1 1)
					(thickness 0.15)
				)
			)
		)
		(property "Dielectric" "X5R"
			(at 0 0 270)
			(unlocked yes)
			(layer "F.Fab")
			(hide yes)
			(effects
				(font
					(size 1 1)
					(thickness 0.15)
				)
			)
		)
		(property "Public" "False"
			(at 0 0 270)
			(unlocked yes)
			(layer "F.Fab")
			(hide yes)
			(effects
				(font
					(size 1 1)
					(thickness 0.15)
				)
			)
		)
		(sheetname "/DCDC/")
		(sheetfile "dcdc.kicad_sch")
		(attr smd)
		(fp_line
			(start -0.3 0.7)
			(end 0.3 0.7)
			(stroke
				(width 0.15)
				(type solid)
			)
			(layer "F.SilkS")
		)
		(fp_line
			(start -0.3 -0.7)
			(end 0.3 -0.7)
			(stroke
				(width 0.15)
				(type solid)
			)
			(layer "F.SilkS")
		)
		(fp_poly
			(pts
				(xy 1.95 -0.9) (xy 1.95 0.9) (xy -1.95 0.9) (xy -1.95 -0.9)
			)
			(stroke
				(width 0.05)
				(type default)
			)
			(fill no)
			(layer "F.CrtYd")
		)
		(fp_poly
			(pts
				(xy -0.95 -0.675001) (xy -0.95 0.675001) (xy 0.95 0.675001) (xy 0.95 -0.675001)
			)
			(stroke
				(width 0.15)
				(type solid)
			)
			(fill no)
			(layer "F.Fab")
		)
		(fp_text user "${REFERENCE}"
			(at -1.899999 3.947 90)
			(layer "F.Fab")
			(effects
				(font
					(size 0.7 0.7)
					(thickness 0.15)
				)
				(justify right top)
			)
		)
		(fp_text user "License: Apache-2.0"
			(at -1.9 4.947 90)
			(layer "F.Fab")
			(effects
				(font
					(size 0.7 0.7)
					(thickness 0.15)
				)
				(justify right top)
			)
		)
		(fp_text user "Author: Antmicro"
			(at -1.9 5.947 90)
			(layer "F.Fab")
			(effects
				(font
					(size 0.7 0.7)
					(thickness 0.15)
				)
				(justify right top)
			)
		)
		(pad "1" smd roundrect
			(at -1.099999 0 270)
			(size 1.2 1.3)
			(layers "F.Cu" "F.Mask" "F.Paste")
			(roundrect_rratio 0.25)
			(net 1 "GND")
			(pintype "passive")
		)
		(pad "2" smd roundrect
			(at 1.099999 0 270)
			(size 1.2 1.3)
			(layers "F.Cu" "F.Mask" "F.Paste")
			(roundrect_rratio 0.25)
			(net 1278 "/DCDC/5V_{AON}_OUT")
			(pintype "passive")
		)
	)
)
